(kicad_pcb
	(version 20241229)
	(generator "pcbnew")
	(generator_version "9.0")
	(general
		(thickness 1.258)
		(legacy_teardrops no)
	)
	(paper "A4")
	(title_block
		(date "2024-05-27")
		(rev "1.1.2")
		(comment 9 "footprint 28 of 64 (J1), pads 198-262 of 262")
	)
	(layers
		(0 "F.Cu" signal)
		(4 "In1.Cu" power)
		(6 "In2.Cu" power)
		(8 "In3.Cu" signal)
		(10 "In4.Cu" signal)
		(2 "B.Cu" signal)
		(9 "F.Adhes" user "F.Adhesive")
		(11 "B.Adhes" user "B.Adhesive")
		(13 "F.Paste" user)
		(15 "B.Paste" user)
		(5 "F.SilkS" user "F.Silkscreen")
		(7 "B.SilkS" user "B.Silkscreen")
		(1 "F.Mask" user)
		(3 "B.Mask" user)
		(17 "Dwgs.User" user "User.Drawings")
		(19 "Cmts.User" user "User.Comments")
		(21 "Eco1.User" user "User.Eco1")
		(23 "Eco2.User" user "User.Eco2")
		(25 "Edge.Cuts" user)
		(27 "Margin" user)
		(31 "F.CrtYd" user "F.Courtyard")
		(29 "B.CrtYd" user "B.Courtyard")
		(35 "F.Fab" user)
		(33 "B.Fab" user)
	)
	(footprint "antmicro-footprints:PCB-Edge_SODIMM_2x130_DDR4"
		(locked yes)
		(layer "F.Cu")
		(at 100 100)
		(property "Reference" "J1"
			(at 0 -4.2 0)
			(layer "F.SilkS")
			(hide yes)
			(effects
				(font
					(size 0.7 0.7)
					(thickness 0.15)
				)
				(justify left bottom)
			)
		)
		(property "Value" "PCB-Edge_SODIMM_2x130_DDR4"
			(at 0 1 0)
			(layer "F.Fab")
			(effects
				(font
					(size 0.7 0.7)
					(thickness 0.15)
				)
				(justify left bottom)
			)
		)
		(property "Description" "DDR SO-DIMM PCB Edge"
			(at 0 0 0)
			(layer "F.Fab")
			(hide yes)
			(effects
				(font
					(size 1.27 1.27)
					(thickness 0.15)
				)
			)
		)
		(property "Author" "Antmicro"
			(at 0 0 0)
			(layer "F.Fab")
			(hide yes)
			(effects
				(font
					(size 1 1)
					(thickness 0.15)
				)
			)
		)
		(property "License" "Apache-2.0"
			(at 0 0 0)
			(layer "F.Fab")
			(hide yes)
			(effects
				(font
					(size 1 1)
					(thickness 0.15)
				)
			)
		)
		(property "MPN" ""
			(at 0 0 0)
			(layer "F.Fab")
			(hide yes)
			(effects
				(font
					(size 1 1)
					(thickness 0.15)
				)
			)
		)
		(property "Manufacturer" ""
			(at 0 0 0)
			(layer "F.Fab")
			(hide yes)
			(effects
				(font
					(size 1 1)
					(thickness 0.15)
				)
			)
		)
		(property "Public" "False"
			(at 0 0 0)
			(layer "F.Fab")
			(hide yes)
			(effects
				(font
					(size 1 1)
					(thickness 0.15)
				)
			)
		)
		(sheetname "SODIMM")
		(sheetfile "sodim.kicad_sch")
		(attr exclude_from_pos_files exclude_from_bom)
		(pad "196" smd rect
			(at 52.173 -1.301)
			(size 0.35 2.5)
			(layers "B.Cu" "B.Mask")
			(net 21 "DQ2")
			(pinfunction "196")
			(pintype "passive")
		)
		(pad "197" smd rect
			(at 52.423 -1.301)
			(size 0.35 2.5)
			(layers "F.Cu" "F.Mask")
			(net 22 "CA1")
			(pinfunction "197")
			(pintype "passive")
		)
		(pad "198" smd rect
			(at 52.673 -1.301)
			(size 0.35 2.5)
			(layers "B.Cu" "B.Mask")
			(net 25 "DQ0")
			(pinfunction "198")
			(pintype "passive")
		)
		(pad "199" smd rect
			(at 52.923 -1.301)
			(size 0.35 2.5)
			(layers "F.Cu" "F.Mask")
			(net 27 "DQS_N")
			(pinfunction "199")
			(pintype "passive")
		)
		(pad "200" smd rect
			(at 53.173 -1.301)
			(size 0.35 2.5)
			(layers "B.Cu" "B.Mask")
			(net 1 "GND")
			(pinfunction "200")
			(pintype "passive")
		)
		(pad "201" smd rect
			(at 53.423 -1.301)
			(size 0.35 2.5)
			(layers "F.Cu" "F.Mask")
			(net 26 "DQS_P")
			(pinfunction "201")
			(pintype "passive")
		)
		(pad "202" smd rect
			(at 53.673 -1.301)
			(size 0.35 2.5)
			(layers "B.Cu" "B.Mask")
			(net 167 "unconnected-(J1-Pad202)")
			(pinfunction "202")
			(pintype "passive+no_connect")
		)
		(pad "203" smd rect
			(at 53.923 -1.301)
			(size 0.35 2.5)
			(layers "F.Cu" "F.Mask")
			(net 3 "RESET_N")
			(pinfunction "203")
			(pintype "passive")
		)
		(pad "204" smd rect
			(at 54.173 -1.301)
			(size 0.35 2.5)
			(layers "B.Cu" "B.Mask")
			(net 168 "unconnected-(J1-Pad204)")
			(pinfunction "204")
			(pintype "passive")
		)
		(pad "205" smd rect
			(at 54.423 -1.301)
			(size 0.35 2.5)
			(layers "F.Cu" "F.Mask")
			(net 54 "TEN")
			(pinfunction "205")
			(pintype "passive")
		)
		(pad "206" smd rect
			(at 54.673 -1.301)
			(size 0.35 2.5)
			(layers "B.Cu" "B.Mask")
			(net 55 "OTD_CA_A")
			(pinfunction "206")
			(pintype "passive")
		)
		(pad "207" smd rect
			(at 54.923 -1.301)
			(size 0.35 2.5)
			(layers "F.Cu" "F.Mask")
			(net 36 "LBDQS")
			(pinfunction "207")
			(pintype "passive")
		)
		(pad "208" smd rect
			(at 55.173 -1.301)
			(size 0.35 2.5)
			(layers "B.Cu" "B.Mask")
			(net 169 "unconnected-(J1-Pad208)")
			(pinfunction "208")
			(pintype "passive+no_connect")
		)
		(pad "209" smd rect
			(at 55.423 -1.301)
			(size 0.35 2.5)
			(layers "F.Cu" "F.Mask")
			(net 38 "LBDQ")
			(pinfunction "209")
			(pintype "passive")
		)
		(pad "210" smd rect
			(at 55.673 -1.301)
			(size 0.35 2.5)
			(layers "B.Cu" "B.Mask")
			(net 1 "GND")
			(pinfunction "210")
			(pintype "passive")
		)
		(pad "211" smd rect
			(at 55.923 -1.301)
			(size 0.35 2.5)
			(layers "F.Cu" "F.Mask")
			(net 1 "GND")
			(pinfunction "211")
			(pintype "passive")
		)
		(pad "212" smd rect
			(at 56.173 -1.301)
			(size 0.35 2.5)
			(layers "B.Cu" "B.Mask")
			(net 170 "unconnected-(J1-Pad212)")
			(pinfunction "212")
			(pintype "passive+no_connect")
		)
		(pad "213" smd rect
			(at 56.423 -1.301)
			(size 0.35 2.5)
			(layers "F.Cu" "F.Mask")
			(net 171 "unconnected-(J1-Pad213)")
			(pinfunction "213")
			(pintype "passive+no_connect")
		)
		(pad "214" smd rect
			(at 56.673 -1.301)
			(size 0.35 2.5)
			(layers "B.Cu" "B.Mask")
			(net 172 "unconnected-(J1-Pad214)")
			(pinfunction "214")
			(pintype "passive+no_connect")
		)
		(pad "215" smd rect
			(at 56.923 -1.301)
			(size 0.35 2.5)
			(layers "F.Cu" "F.Mask")
			(net 173 "unconnected-(J1-Pad215)")
			(pinfunction "215")
			(pintype "passive+no_connect")
		)
		(pad "216" smd rect
			(at 57.173 -1.301)
			(size 0.35 2.5)
			(layers "B.Cu" "B.Mask")
			(net 174 "unconnected-(J1-Pad216)")
			(pinfunction "216")
			(pintype "passive+no_connect")
		)
		(pad "217" smd rect
			(at 57.423 -1.301)
			(size 0.35 2.5)
			(layers "F.Cu" "F.Mask")
			(net 175 "unconnected-(J1-Pad217)")
			(pinfunction "217")
			(pintype "passive+no_connect")
		)
		(pad "218" smd rect
			(at 57.673 -1.301)
			(size 0.35 2.5)
			(layers "B.Cu" "B.Mask")
			(net 176 "unconnected-(J1-Pad218)")
			(pinfunction "218")
			(pintype "passive+no_connect")
		)
		(pad "219" smd rect
			(at 57.923 -1.301)
			(size 0.35 2.5)
			(layers "F.Cu" "F.Mask")
			(net 177 "unconnected-(J1-Pad219)")
			(pinfunction "219")
			(pintype "passive+no_connect")
		)
		(pad "220" smd rect
			(at 58.173 -1.301)
			(size 0.35 2.5)
			(layers "B.Cu" "B.Mask")
			(net 178 "unconnected-(J1-Pad220)")
			(pinfunction "220")
			(pintype "passive+no_connect")
		)
		(pad "221" smd rect
			(at 58.423 -1.301)
			(size 0.35 2.5)
			(layers "F.Cu" "F.Mask")
			(net 179 "unconnected-(J1-Pad221)")
			(pinfunction "221")
			(pintype "passive+no_connect")
		)
		(pad "222" smd rect
			(at 58.673 -1.301)
			(size 0.35 2.5)
			(layers "B.Cu" "B.Mask")
			(net 180 "unconnected-(J1-Pad222)")
			(pinfunction "222")
			(pintype "passive+no_connect")
		)
		(pad "223" smd rect
			(at 58.923 -1.301)
			(size 0.35 2.5)
			(layers "F.Cu" "F.Mask")
			(net 181 "unconnected-(J1-Pad223)")
			(pinfunction "223")
			(pintype "passive+no_connect")
		)
		(pad "224" smd rect
			(at 59.173 -1.301)
			(size 0.35 2.5)
			(layers "B.Cu" "B.Mask")
			(net 182 "unconnected-(J1-Pad224)")
			(pinfunction "224")
			(pintype "passive+no_connect")
		)
		(pad "225" smd rect
			(at 59.423 -1.301)
			(size 0.35 2.5)
			(layers "F.Cu" "F.Mask")
			(net 183 "unconnected-(J1-Pad225)")
			(pinfunction "225")
			(pintype "passive+no_connect")
		)
		(pad "226" smd rect
			(at 59.673 -1.301)
			(size 0.35 2.5)
			(layers "B.Cu" "B.Mask")
			(net 184 "unconnected-(J1-Pad226)")
			(pinfunction "226")
			(pintype "passive+no_connect")
		)
		(pad "227" smd rect
			(at 59.923 -1.301)
			(size 0.35 2.5)
			(layers "F.Cu" "F.Mask")
			(net 185 "unconnected-(J1-Pad227)")
			(pinfunction "227")
			(pintype "passive+no_connect")
		)
		(pad "228" smd rect
			(at 60.173 -1.301)
			(size 0.35 2.5)
			(layers "B.Cu" "B.Mask")
			(net 186 "unconnected-(J1-Pad228)")
			(pinfunction "228")
			(pintype "passive+no_connect")
		)
		(pad "229" smd rect
			(at 60.423 -1.301)
			(size 0.35 2.5)
			(layers "F.Cu" "F.Mask")
			(net 187 "unconnected-(J1-Pad229)")
			(pinfunction "229")
			(pintype "passive+no_connect")
		)
		(pad "230" smd rect
			(at 60.673 -1.301)
			(size 0.35 2.5)
			(layers "B.Cu" "B.Mask")
			(net 188 "unconnected-(J1-Pad230)")
			(pinfunction "230")
			(pintype "passive+no_connect")
		)
		(pad "231" smd rect
			(at 60.923 -1.301)
			(size 0.35 2.5)
			(layers "F.Cu" "F.Mask")
			(net 189 "unconnected-(J1-Pad231)")
			(pinfunction "231")
			(pintype "passive+no_connect")
		)
		(pad "232" smd rect
			(at 61.173 -1.301)
			(size 0.35 2.5)
			(layers "B.Cu" "B.Mask")
			(net 190 "unconnected-(J1-Pad232)")
			(pinfunction "232")
			(pintype "passive+no_connect")
		)
		(pad "233" smd rect
			(at 61.423 -1.301)
			(size 0.35 2.5)
			(layers "F.Cu" "F.Mask")
			(net 191 "unconnected-(J1-Pad233)")
			(pinfunction "233")
			(pintype "passive+no_connect")
		)
		(pad "234" smd rect
			(at 61.673 -1.301)
			(size 0.35 2.5)
			(layers "B.Cu" "B.Mask")
			(net 192 "unconnected-(J1-Pad234)")
			(pinfunction "234")
			(pintype "passive+no_connect")
		)
		(pad "235" smd rect
			(at 61.923 -1.301)
			(size 0.35 2.5)
			(layers "F.Cu" "F.Mask")
			(net 193 "unconnected-(J1-Pad235)")
			(pinfunction "235")
			(pintype "passive+no_connect")
		)
		(pad "236" smd rect
			(at 62.173 -1.301)
			(size 0.35 2.5)
			(layers "B.Cu" "B.Mask")
			(net 194 "unconnected-(J1-Pad236)")
			(pinfunction "236")
			(pintype "passive+no_connect")
		)
		(pad "237" smd rect
			(at 62.423 -1.301)
			(size 0.35 2.5)
			(layers "F.Cu" "F.Mask")
			(net 195 "unconnected-(J1-Pad237)")
			(pinfunction "237")
			(pintype "passive+no_connect")
		)
		(pad "238" smd rect
			(at 62.673 -1.301)
			(size 0.35 2.5)
			(layers "B.Cu" "B.Mask")
			(net 196 "unconnected-(J1-Pad238)")
			(pinfunction "238")
			(pintype "passive+no_connect")
		)
		(pad "239" smd rect
			(at 62.923 -1.301)
			(size 0.35 2.5)
			(layers "F.Cu" "F.Mask")
			(net 197 "unconnected-(J1-Pad239)")
			(pinfunction "239")
			(pintype "passive+no_connect")
		)
		(pad "240" smd rect
			(at 63.173 -1.301)
			(size 0.35 2.5)
			(layers "B.Cu" "B.Mask")
			(net 198 "unconnected-(J1-Pad240)")
			(pinfunction "240")
			(pintype "passive+no_connect")
		)
		(pad "241" smd rect
			(at 63.423 -1.301)
			(size 0.35 2.5)
			(layers "F.Cu" "F.Mask")
			(net 199 "unconnected-(J1-Pad241)")
			(pinfunction "241")
			(pintype "passive+no_connect")
		)
		(pad "242" smd rect
			(at 63.673 -1.301)
			(size 0.35 2.5)
			(layers "B.Cu" "B.Mask")
			(net 200 "unconnected-(J1-Pad242)")
			(pinfunction "242")
			(pintype "passive+no_connect")
		)
		(pad "243" smd rect
			(at 63.923 -1.301)
			(size 0.35 2.5)
			(layers "F.Cu" "F.Mask")
			(net 201 "unconnected-(J1-Pad243)")
			(pinfunction "243")
			(pintype "passive+no_connect")
		)
		(pad "244" smd rect
			(at 64.174 -1.301)
			(size 0.35 2.5)
			(layers "B.Cu" "B.Mask")
			(net 202 "unconnected-(J1-Pad244)")
			(pinfunction "244")
			(pintype "passive+no_connect")
		)
		(pad "245" smd rect
			(at 64.424 -1.301)
			(size 0.35 2.5)
			(layers "F.Cu" "F.Mask")
			(net 203 "unconnected-(J1-Pad245)")
			(pinfunction "245")
			(pintype "passive+no_connect")
		)
		(pad "246" smd rect
			(at 64.674 -1.301)
			(size 0.35 2.5)
			(layers "B.Cu" "B.Mask")
			(net 204 "unconnected-(J1-Pad246)")
			(pinfunction "246")
			(pintype "passive+no_connect")
		)
		(pad "247" smd rect
			(at 64.924 -1.301)
			(size 0.35 2.5)
			(layers "F.Cu" "F.Mask")
			(net 205 "unconnected-(J1-Pad247)")
			(pinfunction "247")
			(pintype "passive+no_connect")
		)
		(pad "248" smd rect
			(at 65.174 -1.301)
			(size 0.35 2.5)
			(layers "B.Cu" "B.Mask")
			(net 206 "unconnected-(J1-Pad248)")
			(pinfunction "248")
			(pintype "passive+no_connect")
		)
		(pad "249" smd rect
			(at 65.424 -1.301)
			(size 0.35 2.5)
			(layers "F.Cu" "F.Mask")
			(net 207 "unconnected-(J1-Pad249)")
			(pinfunction "249")
			(pintype "passive+no_connect")
		)
		(pad "250" smd rect
			(at 65.674 -1.301)
			(size 0.35 2.5)
			(layers "B.Cu" "B.Mask")
			(net 208 "unconnected-(J1-Pad250)")
			(pinfunction "250")
			(pintype "passive+no_connect")
		)
		(pad "251" smd rect
			(at 65.924 -1.301)
			(size 0.35 2.5)
			(layers "F.Cu" "F.Mask")
			(net 209 "unconnected-(J1-Pad251)")
			(pinfunction "251")
			(pintype "passive+no_connect")
		)
		(pad "252" smd rect
			(at 66.174 -1.301)
			(size 0.35 2.5)
			(layers "B.Cu" "B.Mask")
			(net 210 "unconnected-(J1-Pad252)")
			(pinfunction "252")
			(pintype "passive+no_connect")
		)
		(pad "253" smd rect
			(at 66.424 -1.301)
			(size 0.35 2.5)
			(layers "F.Cu" "F.Mask")
			(net 211 "unconnected-(J1-Pad253)")
			(pinfunction "253")
			(pintype "passive+no_connect")
		)
		(pad "254" smd rect
			(at 66.674 -1.301)
			(size 0.35 2.5)
			(layers "B.Cu" "B.Mask")
			(net 212 "unconnected-(J1-Pad254)")
			(pinfunction "254")
			(pintype "passive+no_connect")
		)
		(pad "255" smd rect
			(at 66.924 -1.301)
			(size 0.35 2.5)
			(layers "F.Cu" "F.Mask")
			(net 213 "unconnected-(J1-Pad255)")
			(pinfunction "255")
			(pintype "passive+no_connect")
		)
		(pad "256" smd rect
			(at 67.174 -1.301)
			(size 0.35 2.5)
			(layers "B.Cu" "B.Mask")
			(net 214 "unconnected-(J1-Pad256)")
			(pinfunction "256")
			(pintype "passive+no_connect")
		)
		(pad "257" smd rect
			(at 67.424 -1.301)
			(size 0.35 2.5)
			(layers "F.Cu" "F.Mask")
			(net 215 "unconnected-(J1-Pad257)")
			(pinfunction "257")
			(pintype "passive+no_connect")
		)
		(pad "258" smd rect
			(at 67.674 -1.301)
			(size 0.35 2.5)
			(layers "B.Cu" "B.Mask")
			(net 216 "unconnected-(J1-Pad258)")
			(pinfunction "258")
			(pintype "passive+no_connect")
		)
		(pad "259" smd rect
			(at 67.924 -1.301)
			(size 0.35 2.5)
			(layers "F.Cu" "F.Mask")
			(net 217 "unconnected-(J1-Pad259)")
			(pinfunction "259")
			(pintype "passive+no_connect")
		)
		(pad "260" smd rect
			(at 68.174 -1.301)
			(size 0.35 2.5)
			(layers "B.Cu" "B.Mask")
			(net 218 "unconnected-(J1-Pad260)")
			(pinfunction "260")
			(pintype "passive+no_connect")
		)
	)
)
